# SCM (Grand Teton) — schematic netlist excerpt (pin names and nets, part order shuffled) for the footprints in the layout excerpt that follows; sources: Cadence DE-HDL packaged netlist, KiCad conversion of 12092022_DA0F0TMDCD0_F0T_Management_Board_D_brd_V3_OCP.brd

R169  Q_RES  4.7K 1% CHIP  pkg 0402LF  page 11 : A = P3V3_AUX ; B = RST_PCA9548_SENSOR_N
R849  Q_RES  33.2 1% CHIP  pkg 0402LF  page 21 : A = SMB_BMC_MM16_R5_SCL ; B = SMB_BMC_MM16_R1_SCL

(kicad_pcb
	(version 20260206)
	(generator "pcbnew")
	(generator_version "10.0")
	(general
		(thickness 1.6)
		(legacy_teardrops no)
	)
	(paper "A4")
	(title_block
		(title "12092022_DA0F0TMDCD0_F0T_Management_Board_D_brd_V3_OCP.brd")
		(comment 1 "Grand Teton / footprints 608-609 of 1440")
	)
	(layers
		(0 "F.Cu" signal "TOP")
		(4 "In1.Cu" signal "GND")
		(6 "In2.Cu" signal "IN1")
		(8 "In3.Cu" signal "GND1")
		(10 "In4.Cu" signal "IN2")
		(12 "In5.Cu" signal "VCC")
		(14 "In6.Cu" signal "VCC1")
		(16 "In7.Cu" signal "IN3")
		(18 "In8.Cu" signal "GND2")
		(20 "In9.Cu" signal "IN4")
		(22 "In10.Cu" signal "GND3")
		(2 "B.Cu" signal "BOTTOM")
		(9 "F.Adhes" user "F.Adhesive")
		(11 "B.Adhes" user "B.Adhesive")
		(13 "F.Paste" user "Package Geometry/Pastemask Top")
		(15 "B.Paste" user "Package Geometry/Pastemask Bottom")
		(5 "F.SilkS" user "Ref Des/Silkscreen Top")
		(7 "B.SilkS" user "Ref Des/Silkscreen Bottom")
		(1 "F.Mask" user "Board Geometry/Soldermask Top")
		(3 "B.Mask" user "Board Geometry/Soldermask Bottom")
		(17 "Dwgs.User" user "User.Drawings")
		(19 "Cmts.User" user "User.Comments")
		(21 "Eco1.User" user "User.Eco1")
		(23 "Eco2.User" user "User.Eco2")
		(25 "Edge.Cuts" user "Board Geometry/Outline")
		(27 "Margin" user)
		(31 "F.CrtYd" user "Package Geometry/Place Bound Top")
		(29 "B.CrtYd" user "Package Geometry/Place Bound Bottom")
		(35 "F.Fab" user "Ref Des/Assembly Top")
		(33 "B.Fab" user "Ref Des/Assembly Bottom")
	)
	(footprint ""
		(layer "F.Cu")
		(at 26.1874 -83.7438 90)
		(property "Reference" "R169"
			(at 0 0 90)
			(layer "F.SilkS")
			(hide yes)
			(effects
				(font
					(size 1.27 1.27)
				)
			)
		)
		(property "Value" ""
			(at 0 0 90)
			(layer "F.Fab")
			(effects
				(font
					(size 1.27 1.27)
				)
			)
		)
		(duplicate_pad_numbers_are_jumpers no)
		(fp_line
			(start 0.7874 -0.4064)
			(end 0.7874 0.4064)
			(stroke
				(width 0.1524)
				(type default)
			)
			(layer "F.SilkS")
		)
		(fp_line
			(start -0.7874 -0.4064)
			(end 0.7874 -0.4064)
			(stroke
				(width 0.1524)
				(type default)
			)
			(layer "F.SilkS")
		)
		(fp_line
			(start 0.7874 0.4064)
			(end -0.7874 0.4064)
			(stroke
				(width 0.1524)
				(type default)
			)
			(layer "F.SilkS")
		)
		(fp_line
			(start -0.7874 0.4064)
			(end -0.7874 -0.4064)
			(stroke
				(width 0.1524)
				(type default)
			)
			(layer "F.SilkS")
		)
		(fp_line
			(start -0.12065 -0.305054)
			(end -0.12065 -0.2794)
			(stroke
				(width 0.1)
				(type default)
			)
			(layer "F.Fab")
		)
		(fp_line
			(start -0.67945 -0.305054)
			(end -0.12065 -0.305054)
			(stroke
				(width 0.1)
				(type default)
			)
			(layer "F.Fab")
		)
		(fp_line
			(start 0.67945 -0.3048)
			(end 0.67945 0.3048)
			(stroke
				(width 0.1)
				(type default)
			)
			(layer "F.Fab")
		)
		(fp_line
			(start 0.12065 -0.3048)
			(end 0.67945 -0.3048)
			(stroke
				(width 0.1)
				(type default)
			)
			(layer "F.Fab")
		)
		(fp_line
			(start 0.12065 -0.2794)
			(end 0.12065 -0.3048)
			(stroke
				(width 0.1)
				(type default)
			)
			(layer "F.Fab")
		)
		(fp_line
			(start -0.12065 -0.2794)
			(end 0.12065 -0.2794)
			(stroke
				(width 0.1)
				(type default)
			)
			(layer "F.Fab")
		)
		(fp_line
			(start 0.120396 0.2794)
			(end -0.12065 0.2794)
			(stroke
				(width 0.1)
				(type default)
			)
			(layer "F.Fab")
		)
		(fp_line
			(start -0.12065 0.2794)
			(end -0.12065 0.3048)
			(stroke
				(width 0.1)
				(type default)
			)
			(layer "F.Fab")
		)
		(fp_line
			(start 0.67945 0.3048)
			(end 0.120396 0.3048)
			(stroke
				(width 0.1)
				(type default)
			)
			(layer "F.Fab")
		)
		(fp_line
			(start 0.120396 0.3048)
			(end 0.120396 0.2794)
			(stroke
				(width 0.1)
				(type default)
			)
			(layer "F.Fab")
		)
		(fp_line
			(start -0.12065 0.3048)
			(end -0.67945 0.3048)
			(stroke
				(width 0.1)
				(type default)
			)
			(layer "F.Fab")
		)
		(fp_line
			(start -0.67945 0.3048)
			(end -0.67945 -0.305054)
			(stroke
				(width 0.1)
				(type default)
			)
			(layer "F.Fab")
		)
		(pad "1" smd circle
			(at -0.40005 0 90)
			(size 0 0)
			(layers "F.Cu" "F.Mask" "F.Paste")
			(net "P3V3_AUX")
		)
		(pad "2" smd circle
			(at 0.40005 0 90)
			(size 0 0)
			(layers "F.Cu" "F.Mask" "F.Paste")
			(net "RST_PCA9548_SENSOR_N")
		)
	)
	(footprint ""
		(layer "F.Cu")
		(at 27.2796 -69.0626 90)
		(property "Reference" "R849"
			(at 0 0 90)
			(layer "F.SilkS")
			(hide yes)
			(effects
				(font
					(size 1.27 1.27)
				)
			)
		)
		(property "Value" ""
			(at 0 0 90)
			(layer "F.Fab")
			(effects
				(font
					(size 1.27 1.27)
				)
			)
		)
		(duplicate_pad_numbers_are_jumpers no)
		(fp_line
			(start 0.7874 -0.4064)
			(end 0.7874 0.4064)
			(stroke
				(width 0.1524)
				(type default)
			)
			(layer "F.SilkS")
		)
		(fp_line
			(start -0.7874 -0.4064)
			(end 0.7874 -0.4064)
			(stroke
				(width 0.1524)
				(type default)
			)
			(layer "F.SilkS")
		)
		(fp_line
			(start 0.7874 0.4064)
			(end -0.7874 0.4064)
			(stroke
				(width 0.1524)
				(type default)
			)
			(layer "F.SilkS")
		)
		(fp_line
			(start -0.7874 0.4064)
			(end -0.7874 -0.4064)
			(stroke
				(width 0.1524)
				(type default)
			)
			(layer "F.SilkS")
		)
		(fp_line
			(start -0.12065 -0.305054)
			(end -0.12065 -0.2794)
			(stroke
				(width 0.1)
				(type default)
			)
			(layer "F.Fab")
		)
		(fp_line
			(start -0.67945 -0.305054)
			(end -0.12065 -0.305054)
			(stroke
				(width 0.1)
				(type default)
			)
			(layer "F.Fab")
		)
		(fp_line
			(start 0.67945 -0.3048)
			(end 0.67945 0.3048)
			(stroke
				(width 0.1)
				(type default)
			)
			(layer "F.Fab")
		)
		(fp_line
			(start 0.12065 -0.3048)
			(end 0.67945 -0.3048)
			(stroke
				(width 0.1)
				(type default)
			)
			(layer "F.Fab")
		)
		(fp_line
			(start 0.12065 -0.2794)
			(end 0.12065 -0.3048)
			(stroke
				(width 0.1)
				(type default)
			)
			(layer "F.Fab")
		)
		(fp_line
			(start -0.12065 -0.2794)
			(end 0.12065 -0.2794)
			(stroke
				(width 0.1)
				(type default)
			)
			(layer "F.Fab")
		)
		(fp_line
			(start 0.120396 0.2794)
			(end -0.12065 0.2794)
			(stroke
				(width 0.1)
				(type default)
			)
			(layer "F.Fab")
		)
		(fp_line
			(start -0.12065 0.2794)
			(end -0.12065 0.3048)
			(stroke
				(width 0.1)
				(type default)
			)
			(layer "F.Fab")
		)
		(fp_line
			(start 0.67945 0.3048)
			(end 0.120396 0.3048)
			(stroke
				(width 0.1)
				(type default)
			)
			(layer "F.Fab")
		)
		(fp_line
			(start 0.120396 0.3048)
			(end 0.120396 0.2794)
			(stroke
				(width 0.1)
				(type default)
			)
			(layer "F.Fab")
		)
		(fp_line
			(start -0.12065 0.3048)
			(end -0.67945 0.3048)
			(stroke
				(width 0.1)
				(type default)
			)
			(layer "F.Fab")
		)
		(fp_line
			(start -0.67945 0.3048)
			(end -0.67945 -0.305054)
			(stroke
				(width 0.1)
				(type default)
			)
			(layer "F.Fab")
		)
		(pad "1" smd circle
			(at -0.40005 0 90)
			(size 0 0)
			(layers "F.Cu" "F.Mask" "F.Paste")
			(net "SMB_BMC_MM16_R5_SCL")
		)
		(pad "2" smd circle
			(at 0.40005 0 90)
			(size 0 0)
			(layers "F.Cu" "F.Mask" "F.Paste")
			(net "SMB_BMC_MM16_R1_SCL")
		)
	)
)
